FILE_TYPE = CONNECTIVITY;
{Allegro Design Entry HDL 17.2-2016 S081 (4005846) 1/11/2022}
"PAGE_NUMBER" = 37;
0"NC";
1"PVNN_MAIN_CPU0\g";
2"PVCCINFAON_CPU0\g";
3"PVCCD_HV_CPU0\g";
4"PVCCINFAON_CPU0\g";
5"PVCCIN_CPU0\g";
6"P3V3_AUX\g";
7"PVPP_HBM_CPU0\g";
8"PVNN_MAIN_CPU0\g";
9"PVCCFA_EHV_CPU0\g";
10"GND\g";
%"VCC_CORE"
"1","(4575,1400)","0","logical_power","I10";
;
HDL_POWER"PVCCFA_EHV_CPU0"
CDS_LIB"logical_power";
"A"9;
%"VCC_CORE"
"1","(1325,2200)","0","logical_power","I11";
;
HDL_POWER"PVNN_MAIN_CPU0"
CDS_LIB"logical_power";
"A"8;
%"VCC_CORE"
"1","(1325,1625)","0","logical_power","I12";
;
HDL_POWER"PVPP_HBM_CPU0"
CDS_LIB"logical_power";
"A"7;
%"VCC_CORE"
"1","(625,1950)","0","logical_power","I13";
;
HDL_POWER"P3V3_AUX"
CDS_LIB"logical_power";
"A"6;
%"UNIVERSAL_GND"
"1","(625,1325)","0","logical_power","I14";
;
CDS_LIB"logical_power"
HDL_POWER"GND";
"A"10;
%"Q_CAP"
"1","(625,1600)","0","pure_quanta","I15";
;
PART_NUMBER"CH6101MEB01"
TOLERANCE"20%"
VALUE"10UF"
MATERIAL"X6S"
VOLTAGE"6.3V"
PACK_TYPE"C0402"
$LOCATION"C1"
CDS_LIB"pure_quanta"
CDS_LOCATION"C1"
$SEC"1"
CDS_SEC"1";
"B"
$PN"2"10;
"A"
$PN"1"6;
%"VCC_CORE"
"1","(-3050,4050)","0","logical_power","I2";
;
HDL_POWER"PVCCIN_CPU0"
CDS_LIB"logical_power";
"A"5;
%"VCC_CORE"
"1","(-150,4050)","0","logical_power","I4";
;
HDL_POWER"PVCCINFAON_CPU0"
CDS_LIB"logical_power";
"A"4;
%"VCC_CORE"
"1","(1325,4050)","0","logical_power","I5";
;
HDL_POWER"PVCCD_HV_CPU0"
CDS_LIB"logical_power";
"A"3;
%"VCC_CORE"
"1","(4225,4500)","0","logical_power","I6";
;
HDL_POWER"PVCCINFAON_CPU0"
CDS_LIB"logical_power";
"A"2;
%"SOCKET4677_AZIF0045P001C01CS"
"28","(-1600,2850)","0","pure_quanta","I7";
;
PART_NUMBER"DGA^7000023"
PART_TYPE"SMLF"
MATERIAL"IO"
VALUE"SOCKET4677_AZIF0045-P001C01CS"
$LOCATION"U2"
CDS_LIB"pure_quanta"
NEEDS_NO_SIZE"TRUE"
CDS_LMAN_SYM_OUTLINE"-1050,1150,1050,-1100"
CDS_LOCATION"U2"
$SEC"28"
CDS_SEC"28";
"VCCINFAON33"
$PN"AY18"4;
"VCCINFAON34"
$PN"BA15"4;
"VCCINFAON35"
$PN"BC60"4;
"VCCINFAON36"
$PN"BE15"4;
"VCCINFAON37"
$PN"BE60"4;
"VCCINFAON38"
$PN"BG60"4;
"VCCINFAON39"
$PN"BJ15"4;
"VCCINFAON40"
$PN"BJ60"4;
"VCCINFAON41"
$PN"BK61"4;
"VCCINFAON42"
$PN"BN15"4;
"VCCINFAON43"
$PN"CA15"4;
"VCCINFAON44"
$PN"CE19"4;
"VCCINFAON45"
$PN"CJ11"4;
"VCCINFAON46"
$PN"CJ19"4;
"VCCINFAON47"
$PN"CN19"4;
"VCCINFAON48"
$PN"CP63"4;
"VCCINFAON49"
$PN"CT63"4;
"VCCINFAON50"
$PN"CV61"4;
"VCCINFAON51"
$PN"CV63"4;
"VCCINFAON52"
$PN"CW62"4;
"VCCINFAON53"
$PN"DA21"4;
"VCCIN0"
$PN"BD91"5;
"VCCIN1"
$PN"BE86"5;
"VCCIN2"
$PN"BE88"5;
"VCCIN3"
$PN"BE90"5;
"VCCIN4"
$PN"BF85"5;
"VCCIN5"
$PN"BF87"5;
"VCCIN6"
$PN"BF89"5;
"VCCIN7"
$PN"BF91"5;
"VCCIN8"
$PN"BG84"5;
"VCCIN9"
$PN"BG86"5;
"VCCIN10"
$PN"BG88"5;
"VCCIN11"
$PN"BG90"5;
"VCCIN12"
$PN"BH85"5;
"VCCIN13"
$PN"BH87"5;
"VCCIN14"
$PN"BH89"5;
"VCCIN15"
$PN"BH91"5;
"VCCIN16"
$PN"BK81"5;
"VCCIN17"
$PN"BK83"5;
"VCCIN18"
$PN"BK85"5;
"VCCIN19"
$PN"BK87"5;
"VCCIN20"
$PN"BK89"5;
"VCCIN21"
$PN"BK91"5;
"VCCIN22"
$PN"BL80"5;
"VCCIN23"
$PN"BL82"5;
"VCCIN24"
$PN"BL84"5;
"VCCIN25"
$PN"BL86"5;
"VCCIN26"
$PN"BL88"5;
"VCCIN27"
$PN"BL90"5;
"VCCIN28"
$PN"BM79"5;
"VCCIN29"
$PN"BM81"5;
"VCCIN30"
$PN"BM83"5;
"VCCIN31"
$PN"BM85"5;
"VCCIN32"
$PN"BM87"5;
"VCCIN33"
$PN"BM89"5;
"VCCIN34"
$PN"BM91"5;
"VCCIN35"
$PN"BN33"5;
"VCCIN36"
$PN"BN35"5;
"VCCIN37"
$PN"BN37"5;
"VCCIN38"
$PN"BN39"5;
"VCCIN39"
$PN"BN41"5;
%"SOCKET4677_AZIF0045P001C01CS"
"29","(2775,2450)","0","pure_quanta","I8";
;
PART_NUMBER"DGA^7000023"
PART_TYPE"SMLF"
MATERIAL"IO"
VALUE"SOCKET4677_AZIF0045-P001C01CS"
$LOCATION"U2"
CDS_LIB"pure_quanta"
NEEDS_NO_SIZE"TRUE"
CDS_LMAN_SYM_OUTLINE"-1050,1800,1050,-1750"
CDS_LOCATION"U2"
$SEC"29"
CDS_SEC"29";
"VPP_HBM4"
$PN"CC68"7;
"VPP_HBM3"
$PN"CD67"7;
"VPP_HBM2"
$PN"CE68"7;
"VPP_HBM1"
$PN"CF67"7;
"VPP_HBM"
$PN"CG68"7;
"VCCVNN0"
$PN"BA19"8;
"VCCVNN1"
$PN"BE19"8;
"VCCVNN2"
$PN"BJ19"1;
"VCCVNN3"
$PN"BN19"1;
"VCCINFAON0"
$PN"CE15"2;
"VCCINFAON1"
$PN"CJ15"2;
"VCCINFAON2"
$PN"CJ3"2;
"VCCINFAON3"
$PN"CJ7"2;
"VCCINFAON4"
$PN"CN11"2;
"VCCINFAON5"
$PN"CN15"2;
"VCCINFAON6"
$PN"CN3"2;
"VCCINFAON7"
$PN"CN64"2;
"VCCINFAON8"
$PN"CN66"2;
"VCCINFAON9"
$PN"CN7"2;
"VCCINFAON10"
$PN"CP65"2;
"VCCINFAON11"
$PN"CP67"2;
"VCCINFAON12"
$PN"CT65"2;
"VCCINFAON13"
$PN"CT67"2;
"VCCINFAON14"
$PN"CU11"2;
"VCCINFAON15"
$PN"CU15"2;
"VCCINFAON16"
$PN"CU3"2;
"VCCINFAON17"
$PN"CU64"2;
"VCCINFAON18"
$PN"CU7"2;
"VCCINFAON19"
$PN"CV65"2;
"VCCINFAON20"
$PN"CV67"2;
"VCCINFAON21"
$PN"CW66"2;
"VCCINFAON22"
$PN"CY65"2;
"VCCINFAON23"
$PN"CY67"2;
"VCCINFAON24"
$PN"DA11"2;
"VCCINFAON25"
$PN"DA15"2;
"VCCINFAON26"
$PN"DA64"2;
"VCCINFAON27"
$PN"DE11"2;
"VCCINFAON28"
$PN"DE15"2;
"VCCINFAON29"
$PN"DE3"2;
"VCCINFAON30"
$PN"DJ15"2;
"VCCINFAON31"
$PN"DJ3"2;
"VCCINFAON32"
$PN"DJ7"2;
"VCCINFAON54"
$PN"CR66"2;
"VCCINFAON55"
$PN"CW64"2;
"VCCINFAON56"
$PN"DA3"2;
"VCCINFAON57"
$PN"DA7"2;
"VCCINFAON58"
$PN"DE7"2;
"VCCINFAON59"
$PN"DJ11"2;
"VCCFA_EHV0"
$PN"AA3"9;
"VCCFA_EHV1"
$PN"AE3"9;
"VCCFA_EHV2"
$PN"AJ3"9;
"VCCFA_EHV3"
$PN"AN3"9;
"VCCFA_EHV4"
$PN"AT61"9;
"VCCFA_EHV5"
$PN"AU60"9;
"VCCFA_EHV6"
$PN"AV61"9;
"VCCFA_EHV7"
$PN"AW60"9;
"VCCFA_EHV9"
$PN"U3"9;
"VCCFA_EHV8"
$PN"N3"9;
"VCCD_HV0"
$PN"AT36"3;
"VCCD_HV1"
$PN"AT55"3;
"VCCD_HV2"
$PN"AU3"3;
"VCCD_HV3"
$PN"AU35"3;
"VCCD_HV4"
$PN"AU54"3;
"VCCD_HV5"
$PN"AU7"3;
"VCCD_HV6"
$PN"AV34"3;
"VCCD_HV7"
$PN"AV36"3;
"VCCD_HV8"
$PN"AV53"3;
"VCCD_HV9"
$PN"AV55"3;
"VCCD_HV10"
$PN"BA3"3;
"VCCD_HV11"
$PN"BA7"3;
"VCCD_HV12"
$PN"BE11"3;
"VCCD_HV13"
$PN"BE3"3;
"VCCD_HV14"
$PN"BE7"3;
"VCCD_HV15"
$PN"BJ11"3;
"VCCD_HV16"
$PN"BJ3"3;
"VCCD_HV17"
$PN"BJ7"3;
"VCCD_HV18"
$PN"BN7"3;
"VCCD_HV19"
$PN"CA7"3;
"VCCD_HV20"
$PN"CE7"3;
"VCCD_HV21"
$PN"CW35"3;
"VCCD_HV22"
$PN"CW37"3;
"VCCD_HV23"
$PN"CW52"3;
"VCCD_HV25"
$PN"CW56"3;
"VCCD_HV26"
$PN"CY34"3;
"VCCD_HV24"
$PN"CW54"3;
"VCCD_HV27"
$PN"CY36"3;
"VCCD_HV28"
$PN"CY53"3;
"VCC_3P3_AUX1"
$PN"BA21"6;
"VCC_3P3_AUX0"
$PN"BC21"6;
%"VCC_CORE"
"1","(4575,2050)","0","logical_power","I9";
;
HDL_POWER"PVNN_MAIN_CPU0"
CDS_LIB"logical_power";
"A"1;
END.
